# T6G (Grand Teton) — schematic parts with pin connectivity, parts 5789–5934 of 8303; source: Cadence DE-HDL packaged netlist (pstxprt.dat, pstxnet.dat, pstchip.dat)

R1065  Q_RES  4.7K 5% EMPTY  pkg 0201LF  page 298 : 1 = P1V8_CPU0_RT_1D ; 2 = RST_RT_CPU0_P2_RESET_R_N
R1066  Q_RES  4.7K 5% EMPTY  pkg 0201LF  page 298 : 1 = P1V8_CPU0_RT_1D ; 2 = JTAG_TEST_MODE_RT_CPU0_P2
R1067  Q_RES  0 5% CHIP  pkg 0201LF  page 298 : 1 = SMB_RT_CPU0_P2_R_SCL ; 2 = SMB_RT_CPU0_P2_R2_SCL
R1068  Q_RES  0 5% CHIP  pkg 0201LF  page 298 : 1 = SMB_RT_CPU0_P2_R_SDA ; 2 = SMB_RT_CPU0_P2_R2_SDA
R1069  Q_RES  4.7K 5% EMPTY  pkg 0201LF  page 298 : 1 = P1V8_CPU0_RT_1D ; 2 = GPIO2_RT_CPU0_P2
R1070  Q_RES  10K 1% CHIP  pkg 0201LF  page 298 : 1 = GPIO2_RT_CPU0_P2 ; 2 = GND
R1071  Q_RES  4.7K 5% EMPTY  pkg 0402LF  page 83 : 1 = P3V3_OCP_SFF_EN_R ; 2 = P3V3_AUX
R1072  Q_RES  10K 1% CHIP  pkg 0201LF  page 298 : 1 = GPIO3_RT_CPU0_P2 ; 2 = GND
R1073  Q_RES  4.7K 5% EMPTY  pkg 0201LF  page 298 : 1 = P1V8_CPU0_RT_1D ; 2 = TEST0_RT_CPU0_P2
R1074  Q_RES  4.7K 5% CHIP  pkg 0201LF  page 298 : 1 = TEST0_RT_CPU0_P2 ; 2 = GND
R1075  Q_RES  4.7K 5% EMPTY  pkg 0201LF  page 298 : 1 = P1V8_CPU0_RT_1D ; 2 = TEST1_RT_CPU0_P2
R1076  Q_RES  4.7K 5% CHIP  pkg 0201LF  page 298 : 1 = TEST1_RT_CPU0_P2 ; 2 = GND
R1077  Q_RES  4.7K 5% EMPTY  pkg 0201LF  page 298 : 1 = P1V8_CPU0_RT_1D ; 2 = TEST2_RT_CPU0_P2
R1078  Q_RES  4.7K 5% CHIP  pkg 0201LF  page 298 : 1 = TEST2_RT_CPU0_P2 ; 2 = GND
R1079  Q_RES  4.7K 5% CHIP  pkg 0201LF  page 298 : 1 = JTAG_TEST_MODE_RT_CPU0_P2 ; 2 = GND
R1080  Q_RES  4.7K 5% CHIP  pkg 0201LF  page 298 : 1 = P1V8_CPU0_RT_1D ; 2 = MODE_RT_CPU0_P2
R1081  Q_RES  1K 1% EMPTY  pkg 0201LF  page 299 : 1 = P1V8_CPU0_RT_1D ; 2 = RT_CPU0_P2_VQPS
R1082  Q_RES  200 1% CHIP  pkg 0201LF  page 299 : 1 = RT_CPU0_P2_VQPS ; 2 = GND
R1083  Q_RES  0 5% CHIP  pkg 0201LF  page 299 : 1 = NCF_CPU0_P2_GND ; 2 = GND
R1084  Q_RES  0 5% CHIP  pkg 0201LF  page 299 : 1 = NCF_A1_CPU0_P2_GND ; 2 = GND
R1085  Q_RES  1K 1% CHIP  pkg 0201LF  page 300 : 1 = U16_E2 ; 2 = GND
R1086  Q_RES  0 5% EMPTY  pkg 0402LF  page 312 : 1 = P1V8_CPU0_RT3_1A_1D ; 2 = P1V8_CPU0_RT3_1A
R1087  Q_RES  0 5% EMPTY  pkg 0402LF  page 312 : 1 = P1V8_CPU0_RT3_1A_1D ; 2 = P1V8_CPU0_RT3_1A
R1088  Q_RES  0 5% CHIP  pkg 0201LF  page 309 : 1 = RST_RT_CPU0_P3_PERST_N ; 2 = RST_RT_CPU0_P3_PERST_R_N
R1089  Q_RES  2.2K 5% CHIP  pkg 0402LF  page 250 : 1 = P3V3_AUX ; 2 = SMB_SENSOR_M2_P1_3V3AUX_SCL
R1090  Q_RES  2.2K 5% CHIP  pkg 0402LF  page 250 : 1 = P3V3_AUX ; 2 = SMB_SENSOR_M2_P1_3V3AUX_SDA
R1091  Q_RES  4.7K 5% EMPTY  pkg 0201LF  page 309 : 1 = MODE_RT_CPU0_P3 ; 2 = GND
R1092  Q_RES  10M 1% EMPTY  pkg 0402LF  page 169 : 1 = P3V3_AUX_DSC_G1 ; 2 = GND
R1093  Q_RES  0 5% EMPTY  pkg 0402LF  page 312 : 1 = P1V8_CPU0_RT_1D ; 2 = P1V8_CPU0_RT3_1A_1D
R1094  Q_RES  0 5% EMPTY  pkg 0603LF  page 312 : 1 = P0V9_CPU0_RT_2D ; 2 = P0V9_CPU0_RT3_2A_2D
R1095  Q_RES  0 5% CHIP  pkg 0603LF  page 312 : 1 = P0V9_CPU0_RT3_2A_2D ; 2 = P0V9_CPU0_RT3_2A
R1096  Q_RES  0 5% CHIP  pkg 0201LF  page 309 : 1 = RST_RT_CPU0_P3_RESET_N ; 2 = RST_RT_CPU0_P3_RESET_R_N
R1097  Q_RES  1K 1% CHIP  pkg 0201LF  page 309 : 1 = P1V8_CPU0_RT_1D ; 2 = RT_CPU0_P3_ADDR3
R1098  Q_RES  1K 1% EMPTY  pkg 0201LF  page 309 : 1 = RT_CPU0_P3_ADDR3 ; 2 = GND
R1099  Q_RES  1K 1% EMPTY  pkg 0201LF  page 309 : 1 = P1V8_CPU0_RT_1D ; 2 = RT_CPU0_P3_ADDR2
R1100  Q_RES  20K 1% CHIP  pkg 0201LF  page 309 : 1 = RT_CPU0_P3_ADDR2 ; 2 = GND
R1101  Q_RES  1K 1% EMPTY  pkg 0201LF  page 309 : 1 = P1V8_CPU0_RT_1D ; 2 = RT_CPU0_P3_ADDR1
R1102  Q_RES  1K 1% CHIP  pkg 0201LF  page 309 : 1 = RT_CPU0_P3_ADDR1 ; 2 = GND
R1103  Q_RES  10K 1% CHIP  pkg 0201LF  page 309 : 1 = RST_RT_CPU0_P3_PERST_R_N ; 2 = GND
R1104  Q_RES  10K 1% CHIP  pkg 0201LF  page 309 : 1 = RST_RT_CPU0_P3_RESET_R_N ; 2 = GND
R1105  Q_RES  4.7K 5% EMPTY  pkg 0201LF  page 309 : 1 = P1V8_CPU0_RT_1D ; 2 = RT_CPU0_P3_SCAN_MODE
R1106  Q_RES  200 1% CHIP  pkg 0201LF  page 309 : 1 = RT_CPU0_P3_SCAN_MODE ; 2 = GND
R1107  Q_RES  4.7K 5% EMPTY  pkg 0201LF  page 309 : 1 = P1V8_CPU0_RT_1D ; 2 = RST_RT_CPU0_P3_RESET_R_N
R1108  Q_RES  4.7K 5% EMPTY  pkg 0201LF  page 309 : 1 = P1V8_CPU0_RT_1D ; 2 = JTAG_TEST_MODE_RT_CPU0_P3
R1109  Q_RES  0 5% CHIP  pkg 0201LF  page 309 : 1 = SMB_RT_CPU0_P3_R_SCL ; 2 = SMB_RT_CPU0_P3_R2_SCL
R1110  Q_RES  0 5% CHIP  pkg 0201LF  page 309 : 1 = SMB_RT_CPU0_P3_R_SDA ; 2 = SMB_RT_CPU0_P3_R2_SDA
R1111  Q_RES  4.7K 5% EMPTY  pkg 0201LF  page 309 : 1 = P1V8_CPU0_RT_1D ; 2 = GPIO2_RT_CPU0_P3
R1112  Q_RES  10K 1% CHIP  pkg 0201LF  page 309 : 1 = GPIO2_RT_CPU0_P3 ; 2 = GND
R1113  Q_RES  10K 1% CHIP  pkg 0201LF  page 309 : 1 = GPIO3_RT_CPU0_P3 ; 2 = GND
R1114  Q_RES  4.7K 5% EMPTY  pkg 0201LF  page 309 : 1 = P1V8_CPU0_RT_1D ; 2 = TEST0_RT_CPU0_P3
R1115  Q_RES  4.7K 5% CHIP  pkg 0201LF  page 309 : 1 = TEST0_RT_CPU0_P3 ; 2 = GND
R1116  Q_RES  4.7K 5% EMPTY  pkg 0201LF  page 309 : 1 = P1V8_CPU0_RT_1D ; 2 = TEST1_RT_CPU0_P3
R1117  Q_RES  6.19K 1% CHIP  pkg 0402LF  page 262 : 1 = MB0_P12V_STBY_PWRGD ; 2 = AGND_HSC
R1118  Q_RES  4.7K 5% CHIP  pkg 0201LF  page 309 : 1 = TEST1_RT_CPU0_P3 ; 2 = GND
R1119  Q_RES  4.7K 5% EMPTY  pkg 0201LF  page 309 : 1 = P1V8_CPU0_RT_1D ; 2 = TEST2_RT_CPU0_P3
R1120  Q_RES  4.7K 5% CHIP  pkg 0201LF  page 309 : 1 = TEST2_RT_CPU0_P3 ; 2 = GND
R1121  Q_RES  4.7K 5% CHIP  pkg 0201LF  page 309 : 1 = JTAG_TEST_MODE_RT_CPU0_P3 ; 2 = GND
R1122  Q_RES  4.7K 5% CHIP  pkg 0201LF  page 309 : 1 = P1V8_CPU0_RT_1D ; 2 = MODE_RT_CPU0_P3
R1123  Q_RES  1K 1% EMPTY  pkg 0201LF  page 310 : 1 = P1V8_CPU0_RT_1D ; 2 = RT_CPU0_P3_VQPS
R1124  Q_RES  200 1% CHIP  pkg 0201LF  page 310 : 1 = RT_CPU0_P3_VQPS ; 2 = GND
R1125  Q_RES  0 5% CHIP  pkg 0201LF  page 310 : 1 = NCF_CPU0_P3_GND ; 2 = GND
R1126  Q_RES  0 5% CHIP  pkg 0201LF  page 310 : 1 = NCF_A1_CPU0_P3_GND ; 2 = GND
R1127  Q_RES  1K 1% CHIP  pkg 0201LF  page 311 : 1 = U17_E2 ; 2 = GND
R1128  Q_RES  1K 1% CHIP  pkg 0402LF  page 136 : 1 = P3V3_AUX ; 2 = HP_LVC3_OCP_SFF_PRSNT2
R1129  Q_RES  0 5% CHIP  pkg 0402LF  page 136 : 1 = HP_LVC3_OCP_V3_1_P12V_PWRGD ; 2 = HP_LVC3_OCP_V3_1_P12V_R_PWRGD
R1130  Q_RES  0 5% EMPTY  pkg 0402LF  page 136 : 1 = P12V_OCP_SFF_EN_R ; 2 = P12V_OCP_SFF_EN_R3
R1131  Q_RES  1K 1% CHIP  pkg 0402LF  page 136 : 1 = P3V3_AUX ; 2 = P12V_OCP_SFF_EN_R3
R1132  Q_RES  0 5% CHIP  pkg 0402LF  page 136 : 1 = P12V_OCP_V3_1_PLD_R_PWRGD ; 2 = P12V_OCP_V3_1_PLD_PWRGD
R1133  Q_RES  1K 1% CHIP  pkg 0402LF  page 136 : 1 = P3V3_AUX ; 2 = P12V_OCP_V3_1_PLD_PWRGD
R1134  Q_RES  0 5% CHIP  pkg 0402LF  page 136 : 1 = P12V_OCP_SFF_BUF_EN ; 2 = P12V_OCP_SFF_BUF_EN_R
R1135  Q_RES  0 5% EMPTY  pkg 0402LF  page 247 : 1 = HP_LVC3_OCP_V3_1_R_EN ; 2 = HP_LVC3_OCP_V3_1_P12V_PWRGD
R1136  Q_RES  0 5% EMPTY  pkg 0402LF  page 134 : 1 = HP_LVC3_OCP_V3_1_P12V_PWRGD ; 2 = P3V3_OCP_EN_1_R
R1137  Q_RES  0 5% EMPTY  pkg 0402LF  page 135 : 1 = HP_LVC3_OCP_V3_1_P12V_PWRGD ; 2 = P3V3_OCP_EN_1_R2
R1138  Q_RES  10K 1% CHIP  pkg 0402LF  page 133 : 1 = P3V3_AUX ; 2 = CLK_50M_EN
R1139  Q_RES  0 5% CHIP  pkg 0402LF  page 133 : 1 = CLK_50M_RMII ; 2 = CLK_50M_RMII_R
R1140  Q_RES  27.4 1% CHIP  pkg 0402LF  page 133 : 1 = CLK_50M_BMC_MAC_R ; 2 = CLK_50M_RMII_BMC_OCP
R1141  Q_RES  27.4 1% CHIP  pkg 0402LF  page 133 : 1 = CLK_50M_NCSI_OCP_1 ; 2 = CLK_50M_NCSI_OCP_SFF
R1142  Q_RES  0 5% CHIP  pkg 0402LF  page 136 : 1 = OCP_V3_1_P3V3_PWRGD ; 2 = OCP_V3_1_P3V3_R2_PWRGD
R1143  Q_RES  0 5% CHIP  pkg 0402LF  page 136 : 1 = OCP_V3_1_P3V3_PLD_PWRGD ; 2 = OCP_V3_1_P3V3_PLD_R_PWRGD
R1144  Q_RES  1K 1% CHIP  pkg 0402LF  page 136 : 1 = P3V3_AUX ; 2 = OCP_V3_1_P3V3_PLD_R_PWRGD
R1145  Q_RES  10K 5% EMPTY  pkg 0402LF  page 136 : 1 = P3V3_AUX ; 2 = OCP_SFF_AUX_PWR_EN
R1146  Q_RES  0 5% EMPTY  pkg 0402LF  page 142 : 1 = OCP_V3_2_AUX_PWR_EN_R2 ; 2 = HP_LVC3_OCP_V3_2_PWRGD_R1
R1147  Q_RES  0 5% EMPTY  pkg 0402LF  page 142 : 1 = OCP_V3_2_AUX_PWR_EN_R2 ; 2 = FM_OCP_V3_2_AUX_PWR_R_EN
R1148  Q_RES  0 5% CHIP  pkg 0402LF  page 134 : 1 = HP_LVC3_OCP_V3_1_PRSNT2_N_R ; 2 = HP_LVC3_OCP_SFF_PRSNT2_PLD_N
R1149  Q_RES  1K 1% CHIP  pkg 0402LF  page 142 : 1 = P3V3_AUX ; 2 = HP_LVC3_OCP_V3_2_PRSNT2
R1150  Q_RES  10K 1% CHIP  pkg 0402LF  page 134 : 1 = P3V3_AUX ; 2 = HP_LVC3_OCP_SFF_PRSNT2_PLD_N
R1151  Q_RES  0 5% EMPTY  pkg 0402LF  page 160 : 1 = SMB_CPU0_CPU1_APML_BUF1_SCL_R1 ; 2 = SMB_CPU0_CPU1_APML_BUF1_SCL_R2
R1152  Q_RES  0 5% EMPTY  pkg 0402LF  page 160 : 1 = SMB_CPU0_CPU1_APML_BUF1_SDA_R1 ; 2 = SMB_CPU0_CPU1_APML_BUF1_SDA_R2
R1153  Q_RES  0 5% CHIP  pkg 0402LF  page 160 : 1 = SMB_CPU0_CPU1_SEC_SCL_R1 ; 2 = SMB_CPU0_CPU1_SEC_SCL_R2
R1154  Q_RES  0 5% CHIP  pkg 0402LF  page 160 : 1 = SMB_CPU0_CPU1_SEC_SDA_R1 ; 2 = SMB_CPU0_CPU1_SEC_SDA_R2
R1155  Q_RES  33 5% EMPTY  pkg 0402LF  page 161 : 1 = SMB_APML_CPU0_R_SDA ; 2 = SMB_APML_CPU0_SDA
R1156  Q_RES  33 5% EMPTY  pkg 0402LF  page 161 : 1 = SMB_APML_CPU0_R_SCL ; 2 = SMB_APML_CPU0_SCL
R1157  Q_RES  33 5% EMPTY  pkg 0402LF  page 161 : 1 = SMB_APML_CPU1_R_SCL ; 2 = SMB_APML_CPU1_SCL
R1158  Q_RES  33 5% EMPTY  pkg 0402LF  page 161 : 1 = SMB_APML_CPU1_R_SDA ; 2 = SMB_APML_CPU1_SDA
R1159  Q_RES  0 5% CHIP  pkg 0402LF  page 161 : 1 = SMB_CPU0_SEC_R_SCL ; 2 = SMB_CPU0_SEC_SCL
R1160  Q_RES  0 5% CHIP  pkg 0402LF  page 161 : 1 = SMB_CPU0_SEC_R_SDA ; 2 = SMB_CPU0_SEC_SDA
R1161  Q_RES  0 5% CHIP  pkg 0402LF  page 161 : 1 = SMB_CPU1_SEC_R_SCL ; 2 = SMB_CPU1_SEC_SCL
R1162  Q_RES  0 5% CHIP  pkg 0402LF  page 161 : 1 = SMB_CPU1_SEC_R_SDA ; 2 = SMB_CPU1_SEC_SDA
R1163  Q_RES  0 5% CHIP  pkg 0402LF  page 142 : 1 = HP_LVC3_OCP_V3_2_P12V_PWRGD ; 2 = HP_LVC3_OCP_V3_2_P12V_R_PWRGD
R1164  Q_RES  0 5% EMPTY  pkg 0402LF  page 142 : 1 = P12V_OCP_V3_2_EN_R ; 2 = P12V_OCP_V3_2_EN_R3
R1165  Q_RES  1K 1% CHIP  pkg 0402LF  page 142 : 1 = P3V3_AUX ; 2 = P12V_OCP_V3_2_EN_R3
R1166  Q_RES  0 5% CHIP  pkg 0402LF  page 142 : 1 = P12V_OCP_V3_2_PLD_R_PWRGD ; 2 = P12V_OCP_V3_2_PLD_PWRGD
R1167  Q_RES  1K 1% CHIP  pkg 0402LF  page 142 : 1 = P3V3_AUX ; 2 = P12V_OCP_V3_2_PLD_PWRGD
R1168  Q_RES  0 5% CHIP  pkg 0402LF  page 142 : 1 = P12V_OCP_V3_2_BUF_EN ; 2 = P12V_OCP_V3_2_BUF_EN_R
R1169  Q_RES  0 5% CHIP  pkg 0402LF  page 142 : 1 = OCP_V3_2_P3V3_PWRGD ; 2 = OCP_V3_2_P3V3_R2_PWRGD
R1170  Q_RES  0 5% CHIP  pkg 0402LF  page 142 : 1 = OCP_V3_2_P3V3_PLD_PWRGD ; 2 = OCP_V3_2_P3V3_PLD_R_PWRGD
R1171  Q_RES  1K 1% CHIP  pkg 0402LF  page 142 : 1 = P3V3_AUX ; 2 = OCP_V3_2_P3V3_PLD_R_PWRGD
R1172  Q_RES  10K 5% EMPTY  pkg 0402LF  page 142 : 1 = P3V3_AUX ; 2 = OCP_V3_2_AUX_PWR_EN
R1173  Q_RES  33.2 1% CHIP  pkg 0402LF  page 142 : 1 = OCP_V3_2_P3V3_R3_PWRGD ; 2 = HP_LVC3_OCP_V3_2_PWRGD
R1174  Q_RES  33.2 1% CHIP  pkg 0402LF  page 142 : 1 = RST_PERST_OCP_V3_2_N ; 2 = RST_PERST_OCP_V3_2_R_N
R1175  Q_RES  33.2 1% CHIP  pkg 0402LF  page 142 : 1 = OCP_V3_2_AUX_PWR_EN_R2 ; 2 = OCP_V3_2_AUX_PWR_EN
R1176  Q_RES  10K 1% CHIP  pkg 0402LF  page 142 : 1 = P3V3_AUX ; 2 = FM_OCP_V3_2_AUX_PWR_R_EN
R1177  Q_RES  33.2 1% CHIP  pkg 0402LF  page 142 : 1 = RST_PERST_OCP_V3_2_BUF_R_N ; 2 = RST_PERST_OCP_V3_2_BUF_N
R1178  Q_RES  33.2 1% CHIP  pkg 0402LF  page 142 : 1 = OCP_V3_2_P3V3_R3_PWRGD ; 2 = HP_LVC3_OCP_V3_2_PWRGD_R1
R1179  Q_RES  0 5% CHIP  pkg 0402LF  page 80 : 1 = FM_OCP_V3_2_AUX_PWR_R_EN ; 2 = FM_OCP_V3_2_AUX_PWR_EN
R1180  Q_RES  0 5% EMPTY  pkg 0402LF  page 247 : 1 = HP_LVC3_OCP_V3_2_R_EN ; 2 = HP_LVC3_OCP_V3_2_P12V_PWRGD
R1181  Q_RES  0 5% CHIP  pkg 0402LF  page 140 : 1 = P12V_OCP_V3_2_BUF_EN_R ; 2 = P12V_OCP_EN_2_R
R1182  Q_RES  0 5% EMPTY  pkg 0402LF  page 140 : 1 = HP_LVC3_OCP_V3_2_P12V_PWRGD ; 2 = P3V3_OCP_EN_2_R
R1183  Q_RES  1K 1% CHIP  pkg 0402LF  page 103 : 1 = PWRGD_CHF_CPU1_DIMM ; 2 = PWRGD_CHAF_CPU1
R1184  Q_RES  1K 1% CHIP  pkg 0402LF  page 104 : 1 = PWRGD_CHG_CPU1_DIMM0 ; 2 = PWRGD_CHGL_CPU1
R1185  Q_RES  1K 1% CHIP  pkg 0402LF  page 83 : 1 = PVDDCR_CPU0_P0_PMALERT ; 2 = P3V3_AUX
R1186  Q_RES  1K 1% CHIP  pkg 0402LF  page 83 : 1 = PVDDCR_CPU1_P0_SMB_ALERT ; 2 = P3V3_AUX
R1187  Q_RES  1K 1% CHIP  pkg 0402LF  page 83 : 1 = PVDDCR_CPU0_P1_PMALERT ; 2 = P3V3_AUX
R1188  Q_RES  1K 1% CHIP  pkg 0402LF  page 83 : 1 = PVDDCR_CPU1_P1_SMB_ALERT ; 2 = P3V3_AUX
R1189  Q_RES  1K 1% CHIP  pkg 0402LF  page 83 : 1 = PVDD11_S3_P0_PMALERT ; 2 = P3V3_AUX
R1190  Q_RES  1K 1% CHIP  pkg 0402LF  page 83 : 1 = PVDD11_S3_P1_PMALERT ; 2 = P3V3_AUX
R1191  Q_RES  0 5% CHIP  pkg 0402LF  page 140 : 1 = HP_LVC3_OCP_V3_2_PRSNT2_N_R ; 2 = HP_LVC3_OCP_V3_2_PRSNT2_N
R1192  Q_RES  1K 1% CHIP  pkg 0402LF  page 140 : 1 = P3V3_AUX ; 2 = HP_LVC3_OCP_V3_2_PRSNT2_N
R1193  Q_RES  0 5% CHIP  pkg 0402LF  page 141 : 1 = P12V_OCP_V3_2_BUF_EN_R ; 2 = P12V_OCP_V3_2_EN_2_R3
R1194  Q_RES  200 1% CHIP  pkg 0402LF  page 85 : 1 = P3V3_AUX ; 2 = BMC_FPGA_LED2_R_N
R1195  Q_RES  4.7K 5% EMPTY  pkg 0402LF  page 83 : 1 = P12V_OCP_SFF_EN_R ; 2 = P3V3_AUX
R1196  Q_RES  0 5% EMPTY  pkg 0402LF  page 141 : 1 = HP_LVC3_OCP_V3_2_P12V_PWRGD ; 2 = P3V3_OCP_EN_2
R1197  Q_RES  0 5% EMPTY  pkg 0402LF  page 153 : 1 = ESPI_CPU0_ALERT_P0_N ; 2 = ESPI_CPU0_ALERT_N
R1198  Q_RES  0 5% CHIP  pkg 0201LF  page 186 : 1 = RST_SMB_RT_ROM_R1_N ; 2 = FM_SMB_RT_ROM_MUX3_SEL
R1199  Q_RES  0 5% CHIP  pkg 0201LF  page 186 : 1 = RST_SMB_RT_ROM_R1_N ; 2 = FM_SMB_RT_ROM_MUX2_SEL
R1200  Q_RES  0 5% CHIP  pkg 0201LF  page 186 : 1 = RST_SMB_RT_ROM_R1_N ; 2 = FM_SMB_RT_ROM_MUX4_SEL
R1201  Q_RES  0 5% CHIP  pkg 0201LF  page 186 : 1 = RST_SMB_RT_ROM_R1_N ; 2 = FM_SMB_RT_ROM_MUX1_SEL
R1202  Q_RES  0 5% CHIP  pkg 0402LF  page 81 : 1 = FM_FORCE_ALL_PWRON_R ; 2 = FM_FORCE_ALL_PWRON
R1203  Q_RES  33 5% CHIP  pkg 0402LF  page 81 : 1 = BIOS_DEBUG_MODE_R ; 2 = BIOS_DEBUG_MODE
R1204  Q_RES  0 5% CHIP  pkg 0402LF  page 27 : 1 = FM_BIOS_USB_RECOVERY_R ; 2 = FM_BIOS_USB_RECOVERY
R1205  Q_RES  0 5% CHIP  pkg 0402LF  page 28 : 1 = FM_PASSWORD_CLEAR_R_N ; 2 = FM_PASSWORD_CLEAR_N
R1206  Q_RES  0 5% CHIP  pkg 0201LF  page 186 : 1 = RST_SMB_RT_ROM_R1_N ; 2 = FM_SMB_RT_ROM_MUX7_SEL
R1207  Q_RES  470 1% CHIP  pkg 0402LF  page 166 : 1 = P5V_STBY_PWR_LED ; 2 = P5V_AUX
R1208  Q_RES  470 1% CHIP  pkg 0402LF  page 166 : 1 = PU_P12V_ALL_PWROK_LED ; 2 = P5V_AUX
R1209  Q_RES  0 5% CHIP  pkg 0201LF  page 186 : 1 = RST_SMB_RT_ROM_R1_N ; 2 = FM_SMB_RT_ROM_MUX8_SEL
R1210  Q_RES  0 5% CHIP  pkg 0201LF  page 186 : 1 = RST_SMB_RT_ROM_R1_N ; 2 = FM_SMB_RT_ROM_MUX6_SEL
